#ISCELL
  mstr_misc dns *
  *
#ISCELL
  mstr_symbols design_note *
  *
#ISCELL
  mstr_symbols intel_corp_bpage *
  *
#ISCELL
  mstr_standard offpage *
  page218_i1
#ISCELL
  mstr_standard offpage *
  page218_i10
#CELL
  mstr_discrete res *
  page218_i11
#CELL
  mstr_discrete res *
  page218_i12
#ISCELL
  mstr_symbols p3v3_stby *
  page218_i13
#CELL
  mstr_discrete res *
  page218_i14
#CELL
  mstr_discrete res *
  page218_i15
#CELL
  mstr_discrete res *
  page218_i16
#CELL
  mstr_discrete res *
  page218_i17
#ISCELL
  mstr_standard offpage *
  page218_i18
#ISCELL
  mstr_standard offpage *
  page218_i19
#ISCELL
  mstr_standard offpage *
  page218_i2
#ISCELL
  mstr_standard offpage *
  page218_i20
#CELL
  mstr_discrete res *
  page218_i21
#CELL
  dev_discrete cap_a *
  page218_i22
#CELL
  dev_discrete cap_a *
  page218_i23
#CELL
  mstr_discrete res *
  page218_i24
#CELL
  mstr_discrete res *
  page218_i25
#CELL
  mstr_discrete cap *
  page218_i26
#ISCELL
  mstr_symbols gnd *
  page218_i27
#ISCELL
  mstr_symbols gnd *
  page218_i28
#CELL
  dev_discrete cap_a *
  page218_i29
#ISCELL
  mstr_standard offpage *
  page218_i3
#ISCELL
  mstr_symbols gnd *
  page218_i30
#CELL
  dev_discrete cap_a *
  page218_i31
#ISCELL
  mstr_symbols gnd *
  page218_i32
#ISCELL
  mstr_symbols p3v3_stby *
  page218_i33
#CELL
  mstr_discrete res *
  page218_i34
#CELL
  mstr_discrete res *
  page218_i35
#CELL
  mstr_discrete res *
  page218_i37
#ISCELL
  mstr_symbols gnd *
  page218_i38
#CELL
  mstr_discrete cap *
  page218_i39
#ISCELL
  mstr_standard offpage *
  page218_i4
#CELL
  mstr_discrete res *
  page218_i40
#ISCELL
  mstr_symbols gnd *
  page218_i41
#ISCELL
  mstr_symbols gnd *
  page218_i42
#ISCELL
  mstr_symbols gnd *
  page218_i43
#ISCELL
  mstr_symbols gnd *
  page218_i44
#ISCELL
  mstr_symbols gnd *
  page218_i45
#ISCELL
  mstr_symbols pvccio_cpu0 *
  page218_i46
#CELL
  mstr_discrete res *
  page218_i47
#CELL
  mstr_discrete res *
  page218_i48
#CELL
  mstr_discrete res *
  page218_i50
#ISCELL
  mstr_symbols vcc_core *
  page218_i52
#CELL
  mstr_discrete res *
  page218_i53
#CELL
  mstr_discrete res *
  page218_i54
#CELL
  mstr_discrete cap *
  page218_i55
#ISCELL
  mstr_symbols gnd *
  page218_i56
#CELL
  mstr_discrete res *
  page218_i57
#ISCELL
  mstr_symbols gnd *
  page218_i58
#CELL
  mstr_discrete res *
  page218_i59
#ISCELL
  mstr_symbols pvccio_cpu0 *
  page218_i6
#CELL
  mstr_discrete res *
  page218_i60
#CELL
  mstr_discrete cap *
  page218_i61
#ISCELL
  mstr_standard offpage *
  page218_i62
#ISCELL
  mstr_standard offpage *
  page218_i63
#ISCELL
  mstr_standard offpage *
  page218_i64
#ISCELL
  mstr_standard offpage *
  page218_i65
#ISCELL
  mstr_standard offpage *
  page218_i66
#ISCELL
  mstr_standard offpage *
  page218_i67
#ISCELL
  mstr_standard offpage *
  page218_i68
#ISCELL
  mstr_standard offpage *
  page218_i69
#CELL
  mstr_discrete res *
  page218_i7
#ISCELL
  mstr_standard offpage *
  page218_i70
#ISCELL
  mstr_standard offpage *
  page218_i71
#ISCELL
  mstr_standard offpage *
  page218_i72
#ISCELL
  mstr_standard offpage *
  page218_i73
#ISCELL
  mstr_standard offpage *
  page218_i74
#CELL
  mstr_controller pxm1310b *
  page218_i75
#ISCELL
  mstr_symbols gnd *
  page218_i76
#CELL
  dev_discrete cap_a *
  page218_i77
#ISCELL
  mstr_standard offpage *
  page218_i8
#ISCELL
  mstr_standard offpage *
  page218_i9
